# BASEBOARD_FAB2 (Tioga Pass) — schematic netlist excerpt (pin names and nets, part order shuffled) for the footprints in the layout excerpt that follows; sources: Cadence DE-HDL packaged netlist, KiCad conversion of Wiwynn_Tioga_Pass_MB.brd

U25W8  U74AHCT1G125G-AL5-R-GP-U  pkg TTL-G4  page 252
  \oe#\  = GND
  A  = BMC_VGA_VSYNC
  GND  = GND
  Y  = VGA_REAR_VSYNC_S
  VCC  = P5V_VGA_D

C1F21  SC1U10V2KX-4-GP  10%  pkg SMD-BCG6  page 224 : \1\ = P5V_STBY ; \2\ = GND
C2T2  CAP_A  0.1UF 16V 10% X7R  pkg 0402V  page 185 : A = P3V3 ; B = GND

(kicad_pcb
	(version 20260206)
	(generator "pcbnew")
	(generator_version "10.0")
	(general
		(thickness 1.6)
		(legacy_teardrops no)
	)
	(paper "A4")
	(title_block
		(title "Wiwynn_Tioga_Pass_MB.brd")
		(comment 1 "Tioga Pass / footprints 2975-2977 of 4770")
	)
	(layers
		(0 "F.Cu" signal "TOP")
		(4 "In1.Cu" signal "L2GND")
		(6 "In2.Cu" signal "L3")
		(8 "In3.Cu" signal "L4GND")
		(10 "In4.Cu" signal "L5")
		(12 "In5.Cu" signal "L6GND")
		(14 "In6.Cu" signal "L7VCC")
		(16 "In7.Cu" signal "L8VCC")
		(18 "In8.Cu" signal "L9GND")
		(20 "In9.Cu" signal "L10")
		(22 "In10.Cu" signal "L11GND")
		(24 "In11.Cu" signal "L12")
		(26 "In12.Cu" signal "L13GND")
		(2 "B.Cu" signal "BOTTOM")
		(9 "F.Adhes" user "F.Adhesive")
		(11 "B.Adhes" user "B.Adhesive")
		(13 "F.Paste" user "Package Geometry/Pastemask Top")
		(15 "B.Paste" user "Package Geometry/Pastemask Bottom")
		(5 "F.SilkS" user "Ref Des/Silkscreen Top")
		(7 "B.SilkS" user "Ref Des/Silkscreen Bottom")
		(1 "F.Mask" user "Board Geometry/Soldermask Top")
		(3 "B.Mask" user "Board Geometry/Soldermask Bottom")
		(17 "Dwgs.User" user "User.Drawings")
		(19 "Cmts.User" user "User.Comments")
		(21 "Eco1.User" user "User.Eco1")
		(23 "Eco2.User" user "User.Eco2")
		(25 "Edge.Cuts" user "Board Geometry/Outline")
		(27 "Margin" user)
		(31 "F.CrtYd" user "Package Geometry/Place Bound Top")
		(29 "B.CrtYd" user "Package Geometry/Place Bound Bottom")
		(35 "F.Fab" user "Ref Des/Assembly Top")
		(33 "B.Fab" user "Ref Des/Assembly Bottom")
	)
	(footprint ""
		(layer "B.Cu")
		(at 390.7155 -39.51351 -90)
		(property "Reference" "C2T2"
			(at 0 0 90)
			(layer "B.SilkS")
			(hide yes)
			(effects
				(font
					(size 1.27 1.27)
				)
				(justify mirror)
			)
		)
		(property "Value" ""
			(at 0 0 90)
			(layer "B.Fab")
			(effects
				(font
					(size 1.27 1.27)
				)
				(justify mirror)
			)
		)
		(duplicate_pad_numbers_are_jumpers no)
		(fp_poly
			(pts
				(xy -0.3048 -0.1016) (xy -0.3048 0.9906) (xy 0.3048 0.9906) (xy 0.3048 -0.1016)
			)
			(stroke
				(width 0)
				(type default)
			)
			(fill no)
			(layer "B.CrtYd")
		)
		(fp_line
			(start -0.3048 0.9906)
			(end -0.3048 -0.1016)
			(stroke
				(width 0.1)
				(type default)
			)
			(layer "B.Fab")
		)
		(fp_line
			(start 0.3048 0.9906)
			(end -0.3048 0.9906)
			(stroke
				(width 0.1)
				(type default)
			)
			(layer "B.Fab")
		)
		(fp_line
			(start -0.3048 -0.1016)
			(end 0.3048 -0.1016)
			(stroke
				(width 0.1)
				(type default)
			)
			(layer "B.Fab")
		)
		(fp_line
			(start 0.3048 -0.1016)
			(end 0.3048 0.9906)
			(stroke
				(width 0.1)
				(type default)
			)
			(layer "B.Fab")
		)
		(pad "1" smd rect
			(at 0 0 90)
			(size 0.508 0.508)
			(layers "B.Cu" "B.Mask" "B.Paste")
			(net "P3V3")
		)
		(pad "2" smd rect
			(at 0 0.889 90)
			(size 0.508 0.508)
			(layers "B.Cu" "B.Mask" "B.Paste")
			(net "GND")
		)
		(zone
			(layer "B.Cu")
			(hatch none 0.5)
			(connect_pads
				(clearance 0)
			)
			(min_thickness 0.25)
			(keepout
				(tracks not_allowed)
				(vias allowed)
				(pads allowed)
				(copperpour not_allowed)
				(footprints allowed)
			)
			(placement
				(enabled no)
				(sheetname "")
			)
			(fill
				(thermal_gap 0.5)
				(thermal_bridge_width 0.5)
				(island_removal_mode 0)
			)
			(polygon
				(pts
					(xy 390.0805 -39.25951) (xy 390.0805 -39.76751) (xy 390.4615 -39.76751) (xy 390.4615 -39.25951)
				)
			)
		)
		(zone
			(layer "B.Cu")
			(hatch none 0.5)
			(connect_pads
				(clearance 0)
			)
			(min_thickness 0.25)
			(keepout
				(tracks allowed)
				(vias not_allowed)
				(pads allowed)
				(copperpour not_allowed)
				(footprints allowed)
			)
			(placement
				(enabled no)
				(sheetname "")
			)
			(fill
				(thermal_gap 0.5)
				(thermal_bridge_width 0.5)
				(island_removal_mode 0)
			)
			(polygon
				(pts
					(xy 390.4615 -39.25951) (xy 390.4615 -39.76751) (xy 390.0805 -39.76751) (xy 390.0805 -39.25951)
				)
			)
		)
	)
	(footprint ""
		(layer "B.Cu")
		(at 499.442994 -40.624506)
		(property "Reference" "U25W8"
			(at 0 0 0)
			(layer "B.SilkS")
			(hide yes)
			(effects
				(font
					(size 1.27 1.27)
				)
				(justify mirror)
			)
		)
		(property "Value" "*"
			(at 0 -10.7315 0)
			(unlocked yes)
			(layer "B.Fab")
			(hide yes)
			(effects
				(font
					(size 1.27 1.016)
					(thickness 0.1524)
				)
				(justify mirror)
			)
		)
		(property "Device Type" "U74AHCT1G125G-AL5-R-GP-U_TTL-GA"
			(at 0 -12.2555 0)
			(unlocked yes)
			(layer "B.Fab")
			(hide yes)
			(effects
				(font
					(size 1.27 1.016)
					(thickness 0.1524)
				)
				(justify mirror)
			)
		)
		(duplicate_pad_numbers_are_jumpers no)
		(fp_line
			(start -1.24714 -1.79832)
			(end -1.24714 1.82372)
			(stroke
				(width 0.1524)
				(type default)
			)
			(layer "B.SilkS")
		)
		(fp_line
			(start -1.2446 1.81102)
			(end -1.25476 1.82118)
			(stroke
				(width 0.1524)
				(type default)
			)
			(layer "B.SilkS")
		)
		(fp_line
			(start -1.08712 -1.80848)
			(end 1.23952 -1.80848)
			(stroke
				(width 0.1524)
				(type default)
			)
			(layer "B.SilkS")
		)
		(fp_line
			(start -1.08204 -1.80848)
			(end -1.26492 -1.80848)
			(stroke
				(width 0.1524)
				(type default)
			)
			(layer "B.SilkS")
		)
		(fp_line
			(start -1.08204 1.81102)
			(end 1.4859 1.81102)
			(stroke
				(width 0.1524)
				(type default)
			)
			(layer "B.SilkS")
		)
		(fp_line
			(start -1.06934 1.81102)
			(end -1.2446 1.81102)
			(stroke
				(width 0.1524)
				(type default)
			)
			(layer "B.SilkS")
		)
		(fp_line
			(start 1.2446 1.8034)
			(end 1.2446 -1.8161)
			(stroke
				(width 0.1524)
				(type default)
			)
			(layer "B.SilkS")
		)
		(fp_line
			(start 1.3081 0.49022)
			(end 1.3081 1.7907)
			(stroke
				(width 0.508)
				(type default)
			)
			(layer "B.SilkS")
		)
		(fp_poly
			(pts
				(xy 0.82804 0.10922) (xy -0.82804 0.10922) (xy -0.82804 -0.10795) (xy 0.82804 -0.10795)
			)
			(stroke
				(width 0)
				(type default)
			)
			(fill yes)
			(layer "B.SilkS")
		)
		(fp_poly
			(pts
				(xy 1.5621 2.0447) (xy -1.5621 2.0447) (xy -1.5621 -2.0447) (xy 1.5621 -2.0447)
			)
			(stroke
				(width 0)
				(type default)
			)
			(fill no)
			(layer "B.CrtYd")
		)
		(fp_poly
			(pts
				(xy 1.5621 -2.0447) (xy -1.5621 -2.0447) (xy -1.5621 2.0447) (xy 1.5621 2.0447)
			)
			(stroke
				(width 0)
				(type default)
			)
			(fill no)
			(layer "B.Fab")
		)
		(pad "1" smd rect
			(at 0.65024 0.92202 180)
			(size 0.3556 1.2192)
			(layers "B.Cu" "B.Mask" "B.Paste")
			(net "GND")
		)
		(pad "2" smd rect
			(at 0 0.92202 180)
			(size 0.3556 1.2192)
			(layers "B.Cu" "B.Mask" "B.Paste")
			(net "BMC_VGA_VSYNC")
		)
		(pad "3" smd rect
			(at -0.65024 0.92202 180)
			(size 0.3556 1.2192)
			(layers "B.Cu" "B.Mask" "B.Paste")
			(net "GND")
		)
		(pad "4" smd rect
			(at -0.65024 -0.92075 180)
			(size 0.3556 1.2192)
			(layers "B.Cu" "B.Mask" "B.Paste")
			(net "VGA_REAR_VSYNC_S")
		)
		(pad "5" smd rect
			(at 0.65024 -0.92075 180)
			(size 0.3556 1.2192)
			(layers "B.Cu" "B.Mask" "B.Paste")
			(net "P5V_VGA_D")
		)
	)
	(footprint ""
		(layer "B.Cu")
		(at 4.70408 -13.52296 90)
		(property "Reference" "C1F21"
			(at 0 0 90)
			(layer "B.SilkS")
			(hide yes)
			(effects
				(font
					(size 1.27 1.27)
				)
				(justify mirror)
			)
		)
		(property "Value" "*"
			(at -1.1811 -2.8194 90)
			(unlocked yes)
			(layer "B.Fab")
			(hide yes)
			(effects
				(font
					(size 1.27 1.016)
					(thickness 0.1524)
				)
				(justify mirror)
			)
		)
		(property "Device Type" "SC1U10V2KX-4-GP_SMD-BCG6-SC1U1A"
			(at -1.1811 -4.3434 90)
			(unlocked yes)
			(layer "B.Fab")
			(hide yes)
			(effects
				(font
					(size 1.27 1.016)
					(thickness 0.1524)
				)
				(justify mirror)
			)
		)
		(duplicate_pad_numbers_are_jumpers no)
		(fp_rect
			(start 0.4318 0.9525)
			(end -0.4318 -0.9525)
			(stroke
				(width 0)
				(type default)
			)
			(fill no)
			(layer "B.CrtYd")
		)
		(fp_rect
			(start 0.4318 0.9525)
			(end -0.4318 -0.9525)
			(stroke
				(width 0)
				(type default)
			)
			(fill no)
			(layer "B.Fab")
		)
		(pad "1" smd custom
			(at 0 -0.4445 270)
			(size 0.1524 0.1524)
			(layers "B.Cu" "B.Mask" "B.Paste")
			(net "P5V_STBY")
			(options
				(clearance outline)
				(anchor circle)
			)
			(primitives
				(gr_poly
					(pts
						(arc
							(start 0.3048 0.2032)
							(mid 0.275042 0.275042)
							(end 0.2032 0.3048)
						)
						(arc
							(start -0.2032 0.3048)
							(mid -0.275042 0.275042)
							(end -0.3048 0.2032)
						)
						(arc
							(start -0.3048 -0.2032)
							(mid -0.275042 -0.275042)
							(end -0.2032 -0.3048)
						)
						(arc
							(start 0.2032 -0.3048)
							(mid 0.275042 -0.275042)
							(end 0.3048 -0.2032)
						)
					)
					(width 0)
					(fill yes)
				)
			)
		)
		(pad "2" smd custom
			(at 0 0.4445 270)
			(size 0.1524 0.1524)
			(layers "B.Cu" "B.Mask" "B.Paste")
			(net "GND")
			(options
				(clearance outline)
				(anchor circle)
			)
			(primitives
				(gr_poly
					(pts
						(arc
							(start 0.3048 0.2032)
							(mid 0.275042 0.275042)
							(end 0.2032 0.3048)
						)
						(arc
							(start -0.2032 0.3048)
							(mid -0.275042 0.275042)
							(end -0.3048 0.2032)
						)
						(arc
							(start -0.3048 -0.2032)
							(mid -0.275042 -0.275042)
							(end -0.2032 -0.3048)
						)
						(arc
							(start 0.2032 -0.3048)
							(mid 0.275042 -0.275042)
							(end 0.3048 -0.2032)
						)
					)
					(width 0)
					(fill yes)
				)
			)
		)
	)
)
